(kicad_pcb
	(version 20260206)
	(generator "pcbnew")
	(generator_version "10.0")
	(general
		(thickness 1.6)
		(legacy_teardrops no)
	)
	(paper "A4")
	(title_block
		(title "01162023_DA0F0TEBIF0_F0T_Expander_BD_F_brd_V02_OCP.brd")
		(comment 1 "Grand Teton / footprints 9033-9040 of 9728")
	)
	(layers
		(0 "F.Cu" signal "TOP")
		(4 "In1.Cu" signal "GND")
		(6 "In2.Cu" signal "VCC")
		(8 "In3.Cu" signal "VCC1")
		(10 "In4.Cu" signal "GND1")
		(12 "In5.Cu" signal "IN1")
		(14 "In6.Cu" signal "GND2")
		(16 "In7.Cu" signal "IN2")
		(18 "In8.Cu" signal "GND3")
		(20 "In9.Cu" signal "IN3")
		(22 "In10.Cu" signal "GND4")
		(24 "In11.Cu" signal "IN4")
		(26 "In12.Cu" signal "GND5")
		(28 "In13.Cu" signal "IN5")
		(30 "In14.Cu" signal "GND6")
		(32 "In15.Cu" signal "IN6")
		(34 "In16.Cu" signal "GND7")
		(2 "B.Cu" signal "BOTTOM")
		(9 "F.Adhes" user "F.Adhesive")
		(11 "B.Adhes" user "B.Adhesive")
		(13 "F.Paste" user "Package Geometry/Pastemask Top")
		(15 "B.Paste" user "Package Geometry/Pastemask Bottom")
		(5 "F.SilkS" user "Ref Des/Silkscreen Top")
		(7 "B.SilkS" user "Ref Des/Silkscreen Bottom")
		(1 "F.Mask" user "Board Geometry/Soldermask Top")
		(3 "B.Mask" user "Board Geometry/Soldermask Bottom")
		(17 "Dwgs.User" user "User.Drawings")
		(19 "Cmts.User" user "User.Comments")
		(21 "Eco1.User" user "User.Eco1")
		(23 "Eco2.User" user "User.Eco2")
		(25 "Edge.Cuts" user "Board Geometry/Outline")
		(27 "Margin" user)
		(31 "F.CrtYd" user "Package Geometry/Place Bound Top")
		(29 "B.CrtYd" user "Package Geometry/Place Bound Bottom")
		(35 "F.Fab" user "Ref Des/Assembly Top")
		(33 "B.Fab" user "Ref Des/Assembly Bottom")
	)
	(footprint ""
		(layer "B.Cu")
		(at 293.74973 -288.299906 90)
		(property "Reference" "C3286"
			(at 0 0 90)
			(layer "B.SilkS")
			(hide yes)
			(effects
				(font
					(size 1.27 1.27)
				)
				(justify mirror)
			)
		)
		(property "Value" ""
			(at 0 0 90)
			(layer "B.Fab")
			(effects
				(font
					(size 1.27 1.27)
				)
				(justify mirror)
			)
		)
		(duplicate_pad_numbers_are_jumpers no)
		(fp_line
			(start 0.299974 -0.150114)
			(end -0.299974 -0.150114)
			(stroke
				(width 0.1)
				(type default)
			)
			(layer "B.Fab")
		)
		(fp_line
			(start -0.299974 -0.150114)
			(end -0.299974 0.150114)
			(stroke
				(width 0.1)
				(type default)
			)
			(layer "B.Fab")
		)
		(fp_line
			(start 0.299974 0.150114)
			(end 0.299974 -0.150114)
			(stroke
				(width 0.1)
				(type default)
			)
			(layer "B.Fab")
		)
		(fp_line
			(start -0.299974 0.150114)
			(end 0.299974 0.150114)
			(stroke
				(width 0.1)
				(type default)
			)
			(layer "B.Fab")
		)
		(pad "1" smd rect
			(at 0.2667 0 270)
			(size 0.3048 0.381)
			(layers "B.Cu" "B.Mask" "B.Paste")
			(net "P1V25_PEX2")
		)
		(pad "2" smd rect
			(at -0.2667 0 270)
			(size 0.3048 0.381)
			(layers "B.Cu" "B.Mask" "B.Paste")
			(net "GND")
		)
	)
	(footprint ""
		(layer "B.Cu")
		(at 58.720228 -296.37482)
		(property "Reference" "C1112"
			(at 0 0 0)
			(layer "B.SilkS")
			(hide yes)
			(effects
				(font
					(size 1.27 1.27)
				)
				(justify mirror)
			)
		)
		(property "Value" ""
			(at 0 0 0)
			(layer "B.Fab")
			(effects
				(font
					(size 1.27 1.27)
				)
				(justify mirror)
			)
		)
		(duplicate_pad_numbers_are_jumpers no)
		(fp_line
			(start -0.299974 -0.150114)
			(end -0.299974 0.150114)
			(stroke
				(width 0.1)
				(type default)
			)
			(layer "B.Fab")
		)
		(fp_line
			(start -0.299974 0.150114)
			(end 0.299974 0.150114)
			(stroke
				(width 0.1)
				(type default)
			)
			(layer "B.Fab")
		)
		(fp_line
			(start 0.299974 -0.150114)
			(end -0.299974 -0.150114)
			(stroke
				(width 0.1)
				(type default)
			)
			(layer "B.Fab")
		)
		(fp_line
			(start 0.299974 0.150114)
			(end 0.299974 -0.150114)
			(stroke
				(width 0.1)
				(type default)
			)
			(layer "B.Fab")
		)
		(pad "1" smd rect
			(at 0.2667 0 180)
			(size 0.3048 0.381)
			(layers "B.Cu" "B.Mask" "B.Paste")
			(net "P0V8_PEX0")
		)
		(pad "2" smd rect
			(at -0.2667 0 180)
			(size 0.3048 0.381)
			(layers "B.Cu" "B.Mask" "B.Paste")
			(net "GND")
		)
	)
	(footprint ""
		(layer "B.Cu")
		(at 58.699908 -288.299906 90)
		(property "Reference" "C2937"
			(at 0 0 90)
			(layer "B.SilkS")
			(hide yes)
			(effects
				(font
					(size 1.27 1.27)
				)
				(justify mirror)
			)
		)
		(property "Value" ""
			(at 0 0 90)
			(layer "B.Fab")
			(effects
				(font
					(size 1.27 1.27)
				)
				(justify mirror)
			)
		)
		(duplicate_pad_numbers_are_jumpers no)
		(fp_line
			(start 0.299974 -0.150114)
			(end -0.299974 -0.150114)
			(stroke
				(width 0.1)
				(type default)
			)
			(layer "B.Fab")
		)
		(fp_line
			(start -0.299974 -0.150114)
			(end -0.299974 0.150114)
			(stroke
				(width 0.1)
				(type default)
			)
			(layer "B.Fab")
		)
		(fp_line
			(start 0.299974 0.150114)
			(end 0.299974 -0.150114)
			(stroke
				(width 0.1)
				(type default)
			)
			(layer "B.Fab")
		)
		(fp_line
			(start -0.299974 0.150114)
			(end 0.299974 0.150114)
			(stroke
				(width 0.1)
				(type default)
			)
			(layer "B.Fab")
		)
		(pad "1" smd rect
			(at 0.2667 0 270)
			(size 0.3048 0.381)
			(layers "B.Cu" "B.Mask" "B.Paste")
			(net "P1V25_PEX0")
		)
		(pad "2" smd rect
			(at -0.2667 0 270)
			(size 0.3048 0.381)
			(layers "B.Cu" "B.Mask" "B.Paste")
			(net "GND")
		)
	)
	(footprint ""
		(layer "B.Cu")
		(at 421.571674 -115.608608)
		(property "Reference" "C964"
			(at 0 0 0)
			(layer "B.SilkS")
			(hide yes)
			(effects
				(font
					(size 1.27 1.27)
				)
				(justify mirror)
			)
		)
		(property "Value" ""
			(at 0 0 0)
			(layer "B.Fab")
			(effects
				(font
					(size 1.27 1.27)
				)
				(justify mirror)
			)
		)
		(duplicate_pad_numbers_are_jumpers no)
		(fp_line
			(start -0.7874 -0.4064)
			(end -0.7874 0.4064)
			(stroke
				(width 0.1524)
				(type default)
			)
			(layer "B.SilkS")
		)
		(fp_line
			(start -0.7874 0.4064)
			(end 0.7874 0.4064)
			(stroke
				(width 0.1524)
				(type default)
			)
			(layer "B.SilkS")
		)
		(fp_line
			(start 0.7874 -0.4064)
			(end -0.7874 -0.4064)
			(stroke
				(width 0.1524)
				(type default)
			)
			(layer "B.SilkS")
		)
		(fp_line
			(start 0.7874 0.4064)
			(end 0.7874 -0.4064)
			(stroke
				(width 0.1524)
				(type default)
			)
			(layer "B.SilkS")
		)
		(fp_line
			(start -0.67945 -0.3048)
			(end -0.67945 0.3048)
			(stroke
				(width 0.1)
				(type default)
			)
			(layer "B.Fab")
		)
		(fp_line
			(start -0.67945 0.3048)
			(end -0.120396 0.3048)
			(stroke
				(width 0.1)
				(type default)
			)
			(layer "B.Fab")
		)
		(fp_line
			(start -0.12065 -0.3048)
			(end -0.67945 -0.3048)
			(stroke
				(width 0.1)
				(type default)
			)
			(layer "B.Fab")
		)
		(fp_line
			(start -0.12065 -0.2794)
			(end -0.12065 -0.3048)
			(stroke
				(width 0.1)
				(type default)
			)
			(layer "B.Fab")
		)
		(fp_line
			(start -0.120396 0.2794)
			(end 0.12065 0.2794)
			(stroke
				(width 0.1)
				(type default)
			)
			(layer "B.Fab")
		)
		(fp_line
			(start -0.120396 0.3048)
			(end -0.120396 0.2794)
			(stroke
				(width 0.1)
				(type default)
			)
			(layer "B.Fab")
		)
		(fp_line
			(start 0.12065 -0.305054)
			(end 0.12065 -0.2794)
			(stroke
				(width 0.1)
				(type default)
			)
			(layer "B.Fab")
		)
		(fp_line
			(start 0.12065 -0.2794)
			(end -0.12065 -0.2794)
			(stroke
				(width 0.1)
				(type default)
			)
			(layer "B.Fab")
		)
		(fp_line
			(start 0.12065 0.2794)
			(end 0.12065 0.3048)
			(stroke
				(width 0.1)
				(type default)
			)
			(layer "B.Fab")
		)
		(fp_line
			(start 0.12065 0.3048)
			(end 0.67945 0.3048)
			(stroke
				(width 0.1)
				(type default)
			)
			(layer "B.Fab")
		)
		(fp_line
			(start 0.67945 -0.305054)
			(end 0.12065 -0.305054)
			(stroke
				(width 0.1)
				(type default)
			)
			(layer "B.Fab")
		)
		(fp_line
			(start 0.67945 0.3048)
			(end 0.67945 -0.305054)
			(stroke
				(width 0.1)
				(type default)
			)
			(layer "B.Fab")
		)
		(pad "1" smd circle
			(at 0.40005 0 180)
			(size 0 0)
			(layers "B.Cu" "B.Mask" "B.Paste")
			(net "P3V3_NIC7")
		)
		(pad "2" smd circle
			(at -0.40005 0 180)
			(size 0 0)
			(layers "B.Cu" "B.Mask" "B.Paste")
			(net "GND")
		)
	)
	(footprint ""
		(layer "B.Cu")
		(at 52.049934 -290.199826 90)
		(property "Reference" "C1176"
			(at 0 0 90)
			(layer "B.SilkS")
			(hide yes)
			(effects
				(font
					(size 1.27 1.27)
				)
				(justify mirror)
			)
		)
		(property "Value" ""
			(at 0 0 90)
			(layer "B.Fab")
			(effects
				(font
					(size 1.27 1.27)
				)
				(justify mirror)
			)
		)
		(duplicate_pad_numbers_are_jumpers no)
		(fp_line
			(start 0.299974 -0.150114)
			(end -0.299974 -0.150114)
			(stroke
				(width 0.1)
				(type default)
			)
			(layer "B.Fab")
		)
		(fp_line
			(start -0.299974 -0.150114)
			(end -0.299974 0.150114)
			(stroke
				(width 0.1)
				(type default)
			)
			(layer "B.Fab")
		)
		(fp_line
			(start 0.299974 0.150114)
			(end 0.299974 -0.150114)
			(stroke
				(width 0.1)
				(type default)
			)
			(layer "B.Fab")
		)
		(fp_line
			(start -0.299974 0.150114)
			(end 0.299974 0.150114)
			(stroke
				(width 0.1)
				(type default)
			)
			(layer "B.Fab")
		)
		(pad "1" smd rect
			(at 0.2667 0 270)
			(size 0.3048 0.381)
			(layers "B.Cu" "B.Mask" "B.Paste")
			(net "P0V8_SERDES_VDDA_PEX0")
		)
		(pad "2" smd rect
			(at -0.2667 0 270)
			(size 0.3048 0.381)
			(layers "B.Cu" "B.Mask" "B.Paste")
			(net "GND")
		)
	)
	(footprint ""
		(layer "B.Cu")
		(at 135.941816 -202.663806)
		(property "Reference" "C2602"
			(at 0 0 0)
			(layer "B.SilkS")
			(hide yes)
			(effects
				(font
					(size 1.27 1.27)
				)
				(justify mirror)
			)
		)
		(property "Value" ""
			(at 0 0 0)
			(layer "B.Fab")
			(effects
				(font
					(size 1.27 1.27)
				)
				(justify mirror)
			)
		)
		(duplicate_pad_numbers_are_jumpers no)
		(fp_line
			(start -1.2954 -0.5842)
			(end -1.2954 0.5842)
			(stroke
				(width 0.1524)
				(type default)
			)
			(layer "B.SilkS")
		)
		(fp_line
			(start -1.2954 0.5842)
			(end 1.2954 0.5842)
			(stroke
				(width 0.1524)
				(type default)
			)
			(layer "B.SilkS")
		)
		(fp_line
			(start 1.2954 -0.5842)
			(end -1.2954 -0.5842)
			(stroke
				(width 0.1524)
				(type default)
			)
			(layer "B.SilkS")
		)
		(fp_line
			(start 1.2954 0.5842)
			(end 1.2954 -0.5842)
			(stroke
				(width 0.1524)
				(type default)
			)
			(layer "B.SilkS")
		)
		(fp_line
			(start -1.1938 -0.4064)
			(end -1.1938 0.4064)
			(stroke
				(width 0.1)
				(type default)
			)
			(layer "B.Fab")
		)
		(fp_line
			(start -1.1938 0.4064)
			(end -0.8636 0.4064)
			(stroke
				(width 0.1)
				(type default)
			)
			(layer "B.Fab")
		)
		(fp_line
			(start -0.8636 -0.4572)
			(end -0.8636 -0.4064)
			(stroke
				(width 0.1)
				(type default)
			)
			(layer "B.Fab")
		)
		(fp_line
			(start -0.8636 -0.4064)
			(end -1.1938 -0.4064)
			(stroke
				(width 0.1)
				(type default)
			)
			(layer "B.Fab")
		)
		(fp_line
			(start -0.8636 0.4064)
			(end -0.8636 0.4572)
			(stroke
				(width 0.1)
				(type default)
			)
			(layer "B.Fab")
		)
		(fp_line
			(start -0.8636 0.4572)
			(end 0.8636 0.4572)
			(stroke
				(width 0.1)
				(type default)
			)
			(layer "B.Fab")
		)
		(fp_line
			(start 0.8636 -0.4572)
			(end -0.8636 -0.4572)
			(stroke
				(width 0.1)
				(type default)
			)
			(layer "B.Fab")
		)
		(fp_line
			(start 0.8636 -0.4064)
			(end 0.8636 -0.4572)
			(stroke
				(width 0.1)
				(type default)
			)
			(layer "B.Fab")
		)
		(fp_line
			(start 0.8636 0.4064)
			(end 1.1938 0.4064)
			(stroke
				(width 0.1)
				(type default)
			)
			(layer "B.Fab")
		)
		(fp_line
			(start 0.8636 0.4572)
			(end 0.8636 0.4064)
			(stroke
				(width 0.1)
				(type default)
			)
			(layer "B.Fab")
		)
		(fp_line
			(start 1.1938 -0.4064)
			(end 0.8636 -0.4064)
			(stroke
				(width 0.1)
				(type default)
			)
			(layer "B.Fab")
		)
		(fp_line
			(start 1.1938 0.4064)
			(end 1.1938 -0.4064)
			(stroke
				(width 0.1)
				(type default)
			)
			(layer "B.Fab")
		)
		(pad "1" smd rect
			(at 0.7366 0 270)
			(size 0.7112 0.8128)
			(layers "B.Cu" "B.Mask" "B.Paste")
			(net "P3V3_CLI_VPHY")
		)
		(pad "2" smd rect
			(at -0.7366 0 270)
			(size 0.7112 0.8128)
			(layers "B.Cu" "B.Mask" "B.Paste")
			(net "GND")
		)
	)
	(footprint ""
		(layer "B.Cu")
		(at 378.46 -234.315 90)
		(property "Reference" "C2575"
			(at 0 0 90)
			(layer "B.SilkS")
			(hide yes)
			(effects
				(font
					(size 1.27 1.27)
				)
				(justify mirror)
			)
		)
		(property "Value" ""
			(at 0 0 90)
			(layer "B.Fab")
			(effects
				(font
					(size 1.27 1.27)
				)
				(justify mirror)
			)
		)
		(duplicate_pad_numbers_are_jumpers no)
		(fp_line
			(start 0.7874 -0.4064)
			(end -0.7874 -0.4064)
			(stroke
				(width 0.1524)
				(type default)
			)
			(layer "B.SilkS")
		)
		(fp_line
			(start -0.7874 -0.4064)
			(end -0.7874 0.4064)
			(stroke
				(width 0.1524)
				(type default)
			)
			(layer "B.SilkS")
		)
		(fp_line
			(start 0.7874 0.4064)
			(end 0.7874 -0.4064)
			(stroke
				(width 0.1524)
				(type default)
			)
			(layer "B.SilkS")
		)
		(fp_line
			(start -0.7874 0.4064)
			(end 0.7874 0.4064)
			(stroke
				(width 0.1524)
				(type default)
			)
			(layer "B.SilkS")
		)
		(fp_line
			(start 0.67945 -0.305054)
			(end 0.12065 -0.305054)
			(stroke
				(width 0.1)
				(type default)
			)
			(layer "B.Fab")
		)
		(fp_line
			(start 0.12065 -0.305054)
			(end 0.12065 -0.2794)
			(stroke
				(width 0.1)
				(type default)
			)
			(layer "B.Fab")
		)
		(fp_line
			(start -0.12065 -0.3048)
			(end -0.67945 -0.3048)
			(stroke
				(width 0.1)
				(type default)
			)
			(layer "B.Fab")
		)
		(fp_line
			(start -0.67945 -0.3048)
			(end -0.67945 0.3048)
			(stroke
				(width 0.1)
				(type default)
			)
			(layer "B.Fab")
		)
		(fp_line
			(start 0.12065 -0.2794)
			(end -0.12065 -0.2794)
			(stroke
				(width 0.1)
				(type default)
			)
			(layer "B.Fab")
		)
		(fp_line
			(start -0.12065 -0.2794)
			(end -0.12065 -0.3048)
			(stroke
				(width 0.1)
				(type default)
			)
			(layer "B.Fab")
		)
		(fp_line
			(start 0.12065 0.2794)
			(end 0.12065 0.3048)
			(stroke
				(width 0.1)
				(type default)
			)
			(layer "B.Fab")
		)
		(fp_line
			(start -0.120396 0.2794)
			(end 0.12065 0.2794)
			(stroke
				(width 0.1)
				(type default)
			)
			(layer "B.Fab")
		)
		(fp_line
			(start 0.67945 0.3048)
			(end 0.67945 -0.305054)
			(stroke
				(width 0.1)
				(type default)
			)
			(layer "B.Fab")
		)
		(fp_line
			(start 0.12065 0.3048)
			(end 0.67945 0.3048)
			(stroke
				(width 0.1)
				(type default)
			)
			(layer "B.Fab")
		)
		(fp_line
			(start -0.120396 0.3048)
			(end -0.120396 0.2794)
			(stroke
				(width 0.1)
				(type default)
			)
			(layer "B.Fab")
		)
		(fp_line
			(start -0.67945 0.3048)
			(end -0.120396 0.3048)
			(stroke
				(width 0.1)
				(type default)
			)
			(layer "B.Fab")
		)
		(pad "1" smd circle
			(at 0.40005 0 270)
			(size 0 0)
			(layers "B.Cu" "B.Mask" "B.Paste")
			(net "P1V8_SDB_VCORE")
		)
		(pad "2" smd circle
			(at -0.40005 0 270)
			(size 0 0)
			(layers "B.Cu" "B.Mask" "B.Paste")
			(net "GND")
		)
	)
	(footprint ""
		(layer "B.Cu")
		(at 342.011 -233.553 90)
		(property "Reference" "R3537"
			(at 0 0 90)
			(layer "B.SilkS")
			(hide yes)
			(effects
				(font
					(size 1.27 1.27)
				)
				(justify mirror)
			)
		)
		(property "Value" ""
			(at 0 0 90)
			(layer "B.Fab")
			(effects
				(font
					(size 1.27 1.27)
				)
				(justify mirror)
			)
		)
		(duplicate_pad_numbers_are_jumpers no)
		(fp_line
			(start 0.7874 -0.4064)
			(end -0.7874 -0.4064)
			(stroke
				(width 0.1524)
				(type default)
			)
			(layer "B.SilkS")
		)
		(fp_line
			(start -0.7874 -0.4064)
			(end -0.7874 0.4064)
			(stroke
				(width 0.1524)
				(type default)
			)
			(layer "B.SilkS")
		)
		(fp_line
			(start 0.7874 0.4064)
			(end 0.7874 -0.4064)
			(stroke
				(width 0.1524)
				(type default)
			)
			(layer "B.SilkS")
		)
		(fp_line
			(start -0.7874 0.4064)
			(end 0.7874 0.4064)
			(stroke
				(width 0.1524)
				(type default)
			)
			(layer "B.SilkS")
		)
		(fp_line
			(start 0.67945 -0.305054)
			(end 0.12065 -0.305054)
			(stroke
				(width 0.1)
				(type default)
			)
			(layer "B.Fab")
		)
		(fp_line
			(start 0.12065 -0.305054)
			(end 0.12065 -0.2794)
			(stroke
				(width 0.1)
				(type default)
			)
			(layer "B.Fab")
		)
		(fp_line
			(start -0.12065 -0.3048)
			(end -0.67945 -0.3048)
			(stroke
				(width 0.1)
				(type default)
			)
			(layer "B.Fab")
		)
		(fp_line
			(start -0.67945 -0.3048)
			(end -0.67945 0.3048)
			(stroke
				(width 0.1)
				(type default)
			)
			(layer "B.Fab")
		)
		(fp_line
			(start 0.12065 -0.2794)
			(end -0.12065 -0.2794)
			(stroke
				(width 0.1)
				(type default)
			)
			(layer "B.Fab")
		)
		(fp_line
			(start -0.12065 -0.2794)
			(end -0.12065 -0.3048)
			(stroke
				(width 0.1)
				(type default)
			)
			(layer "B.Fab")
		)
		(fp_line
			(start 0.12065 0.2794)
			(end 0.12065 0.3048)
			(stroke
				(width 0.1)
				(type default)
			)
			(layer "B.Fab")
		)
		(fp_line
			(start -0.120396 0.2794)
			(end 0.12065 0.2794)
			(stroke
				(width 0.1)
				(type default)
			)
			(layer "B.Fab")
		)
		(fp_line
			(start 0.67945 0.3048)
			(end 0.67945 -0.305054)
			(stroke
				(width 0.1)
				(type default)
			)
			(layer "B.Fab")
		)
		(fp_line
			(start 0.12065 0.3048)
			(end 0.67945 0.3048)
			(stroke
				(width 0.1)
				(type default)
			)
			(layer "B.Fab")
		)
		(fp_line
			(start -0.120396 0.3048)
			(end -0.120396 0.2794)
			(stroke
				(width 0.1)
				(type default)
			)
			(layer "B.Fab")
		)
		(fp_line
			(start -0.67945 0.3048)
			(end -0.120396 0.3048)
			(stroke
				(width 0.1)
				(type default)
			)
			(layer "B.Fab")
		)
		(pad "1" smd circle
			(at 0.40005 0 270)
			(size 0 0)
			(layers "B.Cu" "B.Mask" "B.Paste")
			(net "SSD3_PWRDIS_R")
		)
		(pad "2" smd circle
			(at -0.40005 0 270)
			(size 0 0)
			(layers "B.Cu" "B.Mask" "B.Paste")
			(net "SSD3_PWRDIS")
		)
	)
)
